(kicad_pcb
	(version 20260206)
	(generator "pcbnew")
	(generator_version "10.0")
	(general
		(thickness 1.6)
		(legacy_teardrops no)
	)
	(paper "A4")
	(title_block
		(title "03242023_DA0F0TMBIJ0_F0T_Motherboard_J_brd_V01_OCP.brd")
		(comment 1 "Grand Teton / footprints 4159-4164 of 6105")
	)
	(layers
		(0 "F.Cu" signal "TOP")
		(4 "In1.Cu" signal "GND")
		(6 "In2.Cu" signal "IN1")
		(8 "In3.Cu" signal "GND1")
		(10 "In4.Cu" signal "IN2")
		(12 "In5.Cu" signal "GND2")
		(14 "In6.Cu" signal "IN3")
		(16 "In7.Cu" signal "GND3")
		(18 "In8.Cu" signal "VCC")
		(20 "In9.Cu" signal "VCC1")
		(22 "In10.Cu" signal "GND4")
		(24 "In11.Cu" signal "IN4")
		(26 "In12.Cu" signal "GND5")
		(28 "In13.Cu" signal "IN5")
		(30 "In14.Cu" signal "GND6")
		(32 "In15.Cu" signal "IN6")
		(34 "In16.Cu" signal "GND7")
		(2 "B.Cu" signal "BOTTOM")
		(9 "F.Adhes" user "F.Adhesive")
		(11 "B.Adhes" user "B.Adhesive")
		(13 "F.Paste" user "Package Geometry/Pastemask Top")
		(15 "B.Paste" user "Package Geometry/Pastemask Bottom")
		(5 "F.SilkS" user "Ref Des/Silkscreen Top")
		(7 "B.SilkS" user "Ref Des/Silkscreen Bottom")
		(1 "F.Mask" user "Board Geometry/Soldermask Top")
		(3 "B.Mask" user "Board Geometry/Soldermask Bottom")
		(17 "Dwgs.User" user "User.Drawings")
		(19 "Cmts.User" user "User.Comments")
		(21 "Eco1.User" user "User.Eco1")
		(23 "Eco2.User" user "User.Eco2")
		(25 "Edge.Cuts" user "Board Geometry/Outline")
		(27 "Margin" user)
		(31 "F.CrtYd" user "Package Geometry/Place Bound Top")
		(29 "B.CrtYd" user "Package Geometry/Place Bound Bottom")
		(35 "F.Fab" user "Ref Des/Assembly Top")
		(33 "B.Fab" user "Ref Des/Assembly Bottom")
	)
	(footprint ""
		(layer "B.Cu")
		(at 198.47433 -70.903084)
		(property "Reference" "U223"
			(at 3.66141 -3.162554 0)
			(unlocked yes)
			(layer "B.SilkS")
			(effects
				(font
					(size 0.7874 0.5842)
					(thickness 0.1524)
				)
				(justify left mirror)
			)
		)
		(property "Value" ""
			(at 0 0 0)
			(layer "B.Fab")
			(effects
				(font
					(size 1.27 1.27)
				)
				(justify mirror)
			)
		)
		(duplicate_pad_numbers_are_jumpers no)
		(fp_line
			(start -2.0066 -2.5527)
			(end -2.0066 2.5527)
			(stroke
				(width 0.1524)
				(type default)
			)
			(layer "B.SilkS")
		)
		(fp_line
			(start -2.0066 2.5527)
			(end 2.0066 2.5527)
			(stroke
				(width 0.1524)
				(type default)
			)
			(layer "B.SilkS")
		)
		(fp_line
			(start -0.5715 -2.5527)
			(end -2.0066 -2.5527)
			(stroke
				(width 0.1524)
				(type default)
			)
			(layer "B.SilkS")
		)
		(fp_line
			(start 0 -1.9812)
			(end -0.5715 -2.5527)
			(stroke
				(width 0.1524)
				(type default)
			)
			(layer "B.SilkS")
		)
		(fp_line
			(start 0.5715 -2.5527)
			(end 0 -1.9812)
			(stroke
				(width 0.1524)
				(type default)
			)
			(layer "B.SilkS")
		)
		(fp_line
			(start 2.0066 -2.5527)
			(end 0.5715 -2.5527)
			(stroke
				(width 0.1524)
				(type default)
			)
			(layer "B.SilkS")
		)
		(fp_line
			(start 2.0066 2.5527)
			(end 2.0066 -2.5527)
			(stroke
				(width 0.1524)
				(type default)
			)
			(layer "B.SilkS")
		)
		(fp_poly
			(pts
				(xy 4.36372 -1.608328) (xy 3.81 -1.905) (xy 4.36372 -2.233168)
			)
			(stroke
				(width 0)
				(type default)
			)
			(fill yes)
			(layer "B.SilkS")
		)
		(fp_line
			(start -2.249932 -2.549906)
			(end -2.249932 2.549906)
			(stroke
				(width 0.1)
				(type default)
			)
			(layer "B.Fab")
		)
		(fp_line
			(start -2.249932 2.549906)
			(end 2.249932 2.549906)
			(stroke
				(width 0.1)
				(type default)
			)
			(layer "B.Fab")
		)
		(fp_line
			(start 2.249932 -2.549906)
			(end -2.249932 -2.549906)
			(stroke
				(width 0.1)
				(type default)
			)
			(layer "B.Fab")
		)
		(fp_line
			(start 2.249932 2.549906)
			(end 2.249932 -2.549906)
			(stroke
				(width 0.1)
				(type default)
			)
			(layer "B.Fab")
		)
		(fp_poly
			(pts
				(xy 4.36372 -1.608328) (xy 4.36372 -2.233168) (xy 3.81 -1.905)
			)
			(stroke
				(width 0)
				(type default)
			)
			(fill yes)
			(layer "B.Fab")
		)
		(pad "1" smd rect
			(at 2.921 -1.949958 270)
			(size 0.3556 1.4986)
			(layers "B.Cu" "B.Mask" "B.Paste")
			(net "FB_BMC_ISOLATE1")
		)
		(pad "2" smd rect
			(at 2.921 -1.299972 270)
			(size 0.3556 1.4986)
			(layers "B.Cu" "B.Mask" "B.Paste")
			(net "NCSI_BMC_TXD1_R1")
		)
		(pad "3" smd rect
			(at 2.921 -0.649986 270)
			(size 0.3556 1.4986)
			(layers "B.Cu" "B.Mask" "B.Paste")
			(net "NCSI_OCP_V3_2_TXD1")
		)
		(pad "4" smd rect
			(at 2.921 0 270)
			(size 0.3556 1.4986)
			(layers "B.Cu" "B.Mask" "B.Paste")
			(net "FB_BMC_ISOLATE1")
		)
		(pad "5" smd rect
			(at 2.921 0.649986 270)
			(size 0.3556 1.4986)
			(layers "B.Cu" "B.Mask" "B.Paste")
			(net "NCSI_BMC_TXD0_R1")
		)
		(pad "6" smd rect
			(at 2.921 1.299972 270)
			(size 0.3556 1.4986)
			(layers "B.Cu" "B.Mask" "B.Paste")
			(net "NCSI_OCP_V3_2_TXD0")
		)
		(pad "7" smd rect
			(at 2.921 1.949958 270)
			(size 0.3556 1.4986)
			(layers "B.Cu" "B.Mask" "B.Paste")
			(net "GND")
		)
		(pad "8" smd rect
			(at -2.921 1.949958 270)
			(size 0.3556 1.4986)
			(layers "B.Cu" "B.Mask" "B.Paste")
			(net "NCSI_OCP_V3_2_TX_EN")
		)
		(pad "9" smd rect
			(at -2.921 1.299972 270)
			(size 0.3556 1.4986)
			(layers "B.Cu" "B.Mask" "B.Paste")
			(net "NCSI_BMC_TX_EN_R1")
		)
		(pad "10" smd rect
			(at -2.921 0.649986 270)
			(size 0.3556 1.4986)
			(layers "B.Cu" "B.Mask" "B.Paste")
			(net "FB_BMC_ISOLATE1")
		)
		(pad "11" smd rect
			(at -2.921 0 270)
			(size 0.3556 1.4986)
			(layers "B.Cu" "B.Mask" "B.Paste")
			(net "OCP_V3_2_ISO2_RBT_ARB_OUT")
		)
		(pad "12" smd rect
			(at -2.921 -0.649986 270)
			(size 0.3556 1.4986)
			(layers "B.Cu" "B.Mask" "B.Paste")
			(net "OCP_V3_2_RBT_ARB_OUT")
		)
		(pad "13" smd rect
			(at -2.921 -1.299972 270)
			(size 0.3556 1.4986)
			(layers "B.Cu" "B.Mask" "B.Paste")
			(net "FB_BMC_ISOLATE1")
		)
		(pad "14" smd rect
			(at -2.921 -1.949958 270)
			(size 0.3556 1.4986)
			(layers "B.Cu" "B.Mask" "B.Paste")
			(net "P3V3_AUX")
		)
	)
	(footprint ""
		(layer "B.Cu")
		(at 451.812406 -317.15583 90)
		(property "Reference" "R3890"
			(at 0 0 90)
			(layer "B.SilkS")
			(hide yes)
			(effects
				(font
					(size 1.27 1.27)
				)
				(justify mirror)
			)
		)
		(property "Value" ""
			(at 0 0 90)
			(layer "B.Fab")
			(effects
				(font
					(size 1.27 1.27)
				)
				(justify mirror)
			)
		)
		(duplicate_pad_numbers_are_jumpers no)
		(fp_line
			(start 0.7874 -0.4064)
			(end -0.7874 -0.4064)
			(stroke
				(width 0.1524)
				(type default)
			)
			(layer "B.SilkS")
		)
		(fp_line
			(start -0.7874 -0.4064)
			(end -0.7874 0.4064)
			(stroke
				(width 0.1524)
				(type default)
			)
			(layer "B.SilkS")
		)
		(fp_line
			(start 0.7874 0.4064)
			(end 0.7874 -0.4064)
			(stroke
				(width 0.1524)
				(type default)
			)
			(layer "B.SilkS")
		)
		(fp_line
			(start -0.7874 0.4064)
			(end 0.7874 0.4064)
			(stroke
				(width 0.1524)
				(type default)
			)
			(layer "B.SilkS")
		)
		(fp_line
			(start 0.67945 -0.305054)
			(end 0.12065 -0.305054)
			(stroke
				(width 0.1)
				(type default)
			)
			(layer "B.Fab")
		)
		(fp_line
			(start 0.12065 -0.305054)
			(end 0.12065 -0.2794)
			(stroke
				(width 0.1)
				(type default)
			)
			(layer "B.Fab")
		)
		(fp_line
			(start -0.12065 -0.3048)
			(end -0.67945 -0.3048)
			(stroke
				(width 0.1)
				(type default)
			)
			(layer "B.Fab")
		)
		(fp_line
			(start -0.67945 -0.3048)
			(end -0.67945 0.3048)
			(stroke
				(width 0.1)
				(type default)
			)
			(layer "B.Fab")
		)
		(fp_line
			(start 0.12065 -0.2794)
			(end -0.12065 -0.2794)
			(stroke
				(width 0.1)
				(type default)
			)
			(layer "B.Fab")
		)
		(fp_line
			(start -0.12065 -0.2794)
			(end -0.12065 -0.3048)
			(stroke
				(width 0.1)
				(type default)
			)
			(layer "B.Fab")
		)
		(fp_line
			(start 0.12065 0.2794)
			(end 0.12065 0.3048)
			(stroke
				(width 0.1)
				(type default)
			)
			(layer "B.Fab")
		)
		(fp_line
			(start -0.120396 0.2794)
			(end 0.12065 0.2794)
			(stroke
				(width 0.1)
				(type default)
			)
			(layer "B.Fab")
		)
		(fp_line
			(start 0.67945 0.3048)
			(end 0.67945 -0.305054)
			(stroke
				(width 0.1)
				(type default)
			)
			(layer "B.Fab")
		)
		(fp_line
			(start 0.12065 0.3048)
			(end 0.67945 0.3048)
			(stroke
				(width 0.1)
				(type default)
			)
			(layer "B.Fab")
		)
		(fp_line
			(start -0.120396 0.3048)
			(end -0.120396 0.2794)
			(stroke
				(width 0.1)
				(type default)
			)
			(layer "B.Fab")
		)
		(fp_line
			(start -0.67945 0.3048)
			(end -0.120396 0.3048)
			(stroke
				(width 0.1)
				(type default)
			)
			(layer "B.Fab")
		)
		(pad "1" smd circle
			(at 0.40005 0 270)
			(size 0 0)
			(layers "B.Cu" "B.Mask" "B.Paste")
			(net "I3C_SPD_DDREFGH_CPU0_LVC1_SCL_7")
		)
		(pad "2" smd circle
			(at -0.40005 0 270)
			(size 0 0)
			(layers "B.Cu" "B.Mask" "B.Paste")
			(net "I3C_SPD_DDREFGH_CPU0_LVC1_SCL")
		)
	)
	(footprint ""
		(layer "B.Cu")
		(at 426.892212 -121.685812 180)
		(property "Reference" "PR1390"
			(at 0 0 0)
			(layer "B.SilkS")
			(hide yes)
			(effects
				(font
					(size 1.27 1.27)
				)
				(justify mirror)
			)
		)
		(property "Value" ""
			(at 0 0 0)
			(layer "B.Fab")
			(effects
				(font
					(size 1.27 1.27)
				)
				(justify mirror)
			)
		)
		(duplicate_pad_numbers_are_jumpers no)
		(fp_line
			(start 0.7874 0.4064)
			(end 0.7874 -0.4064)
			(stroke
				(width 0.1524)
				(type default)
			)
			(layer "B.SilkS")
		)
		(fp_line
			(start 0.7874 -0.4064)
			(end -0.7874 -0.4064)
			(stroke
				(width 0.1524)
				(type default)
			)
			(layer "B.SilkS")
		)
		(fp_line
			(start -0.7874 0.4064)
			(end 0.7874 0.4064)
			(stroke
				(width 0.1524)
				(type default)
			)
			(layer "B.SilkS")
		)
		(fp_line
			(start -0.7874 -0.4064)
			(end -0.7874 0.4064)
			(stroke
				(width 0.1524)
				(type default)
			)
			(layer "B.SilkS")
		)
		(fp_line
			(start 0.67945 0.3048)
			(end 0.67945 -0.305054)
			(stroke
				(width 0.1)
				(type default)
			)
			(layer "B.Fab")
		)
		(fp_line
			(start 0.67945 -0.305054)
			(end 0.12065 -0.305054)
			(stroke
				(width 0.1)
				(type default)
			)
			(layer "B.Fab")
		)
		(fp_line
			(start 0.12065 0.3048)
			(end 0.67945 0.3048)
			(stroke
				(width 0.1)
				(type default)
			)
			(layer "B.Fab")
		)
		(fp_line
			(start 0.12065 0.2794)
			(end 0.12065 0.3048)
			(stroke
				(width 0.1)
				(type default)
			)
			(layer "B.Fab")
		)
		(fp_line
			(start 0.12065 -0.2794)
			(end -0.12065 -0.2794)
			(stroke
				(width 0.1)
				(type default)
			)
			(layer "B.Fab")
		)
		(fp_line
			(start 0.12065 -0.305054)
			(end 0.12065 -0.2794)
			(stroke
				(width 0.1)
				(type default)
			)
			(layer "B.Fab")
		)
		(fp_line
			(start -0.120396 0.3048)
			(end -0.120396 0.2794)
			(stroke
				(width 0.1)
				(type default)
			)
			(layer "B.Fab")
		)
		(fp_line
			(start -0.120396 0.2794)
			(end 0.12065 0.2794)
			(stroke
				(width 0.1)
				(type default)
			)
			(layer "B.Fab")
		)
		(fp_line
			(start -0.12065 -0.2794)
			(end -0.12065 -0.3048)
			(stroke
				(width 0.1)
				(type default)
			)
			(layer "B.Fab")
		)
		(fp_line
			(start -0.12065 -0.3048)
			(end -0.67945 -0.3048)
			(stroke
				(width 0.1)
				(type default)
			)
			(layer "B.Fab")
		)
		(fp_line
			(start -0.67945 0.3048)
			(end -0.120396 0.3048)
			(stroke
				(width 0.1)
				(type default)
			)
			(layer "B.Fab")
		)
		(fp_line
			(start -0.67945 -0.3048)
			(end -0.67945 0.3048)
			(stroke
				(width 0.1)
				(type default)
			)
			(layer "B.Fab")
		)
		(pad "1" smd circle
			(at 0.40005 0)
			(size 0 0)
			(layers "B.Cu" "B.Mask" "B.Paste")
			(net "P12V_AUX_CPU0_DIMM_ISEN_N")
		)
		(pad "2" smd circle
			(at -0.40005 0)
			(size 0 0)
			(layers "B.Cu" "B.Mask" "B.Paste")
			(net "PVCCD_HV_CPU0_ISENSE_N")
		)
	)
	(footprint ""
		(layer "B.Cu")
		(at 70.012306 -219.823538 90)
		(property "Reference" "R1243"
			(at 0 0 90)
			(layer "B.SilkS")
			(hide yes)
			(effects
				(font
					(size 1.27 1.27)
				)
				(justify mirror)
			)
		)
		(property "Value" ""
			(at 0 0 90)
			(layer "B.Fab")
			(effects
				(font
					(size 1.27 1.27)
				)
				(justify mirror)
			)
		)
		(duplicate_pad_numbers_are_jumpers no)
		(fp_line
			(start 0.7874 -0.4064)
			(end -0.7874 -0.4064)
			(stroke
				(width 0.1524)
				(type default)
			)
			(layer "B.SilkS")
		)
		(fp_line
			(start -0.7874 -0.4064)
			(end -0.7874 0.4064)
			(stroke
				(width 0.1524)
				(type default)
			)
			(layer "B.SilkS")
		)
		(fp_line
			(start 0.7874 0.4064)
			(end 0.7874 -0.4064)
			(stroke
				(width 0.1524)
				(type default)
			)
			(layer "B.SilkS")
		)
		(fp_line
			(start -0.7874 0.4064)
			(end 0.7874 0.4064)
			(stroke
				(width 0.1524)
				(type default)
			)
			(layer "B.SilkS")
		)
		(fp_line
			(start 0.67945 -0.305054)
			(end 0.12065 -0.305054)
			(stroke
				(width 0.1)
				(type default)
			)
			(layer "B.Fab")
		)
		(fp_line
			(start 0.12065 -0.305054)
			(end 0.12065 -0.2794)
			(stroke
				(width 0.1)
				(type default)
			)
			(layer "B.Fab")
		)
		(fp_line
			(start -0.12065 -0.3048)
			(end -0.67945 -0.3048)
			(stroke
				(width 0.1)
				(type default)
			)
			(layer "B.Fab")
		)
		(fp_line
			(start -0.67945 -0.3048)
			(end -0.67945 0.3048)
			(stroke
				(width 0.1)
				(type default)
			)
			(layer "B.Fab")
		)
		(fp_line
			(start 0.12065 -0.2794)
			(end -0.12065 -0.2794)
			(stroke
				(width 0.1)
				(type default)
			)
			(layer "B.Fab")
		)
		(fp_line
			(start -0.12065 -0.2794)
			(end -0.12065 -0.3048)
			(stroke
				(width 0.1)
				(type default)
			)
			(layer "B.Fab")
		)
		(fp_line
			(start 0.12065 0.2794)
			(end 0.12065 0.3048)
			(stroke
				(width 0.1)
				(type default)
			)
			(layer "B.Fab")
		)
		(fp_line
			(start -0.120396 0.2794)
			(end 0.12065 0.2794)
			(stroke
				(width 0.1)
				(type default)
			)
			(layer "B.Fab")
		)
		(fp_line
			(start 0.67945 0.3048)
			(end 0.67945 -0.305054)
			(stroke
				(width 0.1)
				(type default)
			)
			(layer "B.Fab")
		)
		(fp_line
			(start 0.12065 0.3048)
			(end 0.67945 0.3048)
			(stroke
				(width 0.1)
				(type default)
			)
			(layer "B.Fab")
		)
		(fp_line
			(start -0.120396 0.3048)
			(end -0.120396 0.2794)
			(stroke
				(width 0.1)
				(type default)
			)
			(layer "B.Fab")
		)
		(fp_line
			(start -0.67945 0.3048)
			(end -0.120396 0.3048)
			(stroke
				(width 0.1)
				(type default)
			)
			(layer "B.Fab")
		)
		(pad "1" smd circle
			(at 0.40005 0 270)
			(size 0 0)
			(layers "B.Cu" "B.Mask" "B.Paste")
			(net "H_PMAX_TRIGGER_IO_CPU1")
		)
		(pad "2" smd circle
			(at -0.40005 0 270)
			(size 0 0)
			(layers "B.Cu" "B.Mask" "B.Paste")
			(net "GND")
		)
	)
	(footprint ""
		(layer "B.Cu")
		(at 81.422494 -45.785786 -90)
		(property "Reference" "R3633"
			(at 0 0 90)
			(layer "B.SilkS")
			(hide yes)
			(effects
				(font
					(size 1.27 1.27)
				)
				(justify mirror)
			)
		)
		(property "Value" ""
			(at 0 0 90)
			(layer "B.Fab")
			(effects
				(font
					(size 1.27 1.27)
				)
				(justify mirror)
			)
		)
		(duplicate_pad_numbers_are_jumpers no)
		(fp_line
			(start -4.0386 1.7526)
			(end 4.0386 1.7526)
			(stroke
				(width 0.1524)
				(type default)
			)
			(layer "B.SilkS")
		)
		(fp_line
			(start 4.0386 1.7526)
			(end 4.0386 -1.7526)
			(stroke
				(width 0.1524)
				(type default)
			)
			(layer "B.SilkS")
		)
		(fp_line
			(start -4.0386 -1.7526)
			(end -4.0386 1.7526)
			(stroke
				(width 0.1524)
				(type default)
			)
			(layer "B.SilkS")
		)
		(fp_line
			(start 4.0386 -1.7526)
			(end -4.0386 -1.7526)
			(stroke
				(width 0.1524)
				(type default)
			)
			(layer "B.SilkS")
		)
		(fp_line
			(start -4.0386 1.7526)
			(end 4.0386 1.7526)
			(stroke
				(width 0.1)
				(type default)
			)
			(layer "B.Fab")
		)
		(fp_line
			(start 4.0386 1.7526)
			(end 4.0386 -1.7526)
			(stroke
				(width 0.1)
				(type default)
			)
			(layer "B.Fab")
		)
		(fp_line
			(start -4.0386 -1.7526)
			(end -4.0386 1.7526)
			(stroke
				(width 0.1)
				(type default)
			)
			(layer "B.Fab")
		)
		(fp_line
			(start 4.0386 -1.7526)
			(end -4.0386 -1.7526)
			(stroke
				(width 0.1)
				(type default)
			)
			(layer "B.Fab")
		)
		(pad "1" smd rect
			(at 3.1115 0 90)
			(size 1.524 3.2004)
			(layers "B.Cu" "B.Mask" "B.Paste")
			(net "P3V3_OCP_V3_2")
		)
		(pad "2" smd rect
			(at -3.1115 0 90)
			(size 1.524 3.2004)
			(layers "B.Cu" "B.Mask" "B.Paste")
			(net "P3V3_OCP_V3_2_R")
		)
	)
	(footprint ""
		(layer "B.Cu")
		(at 51.95316 -143.759428)
		(property "Reference" "PR1797"
			(at 0 0 0)
			(layer "B.SilkS")
			(hide yes)
			(effects
				(font
					(size 1.27 1.27)
				)
				(justify mirror)
			)
		)
		(property "Value" ""
			(at 0 0 0)
			(layer "B.Fab")
			(effects
				(font
					(size 1.27 1.27)
				)
				(justify mirror)
			)
		)
		(duplicate_pad_numbers_are_jumpers no)
		(fp_line
			(start -0.7874 -0.4064)
			(end -0.7874 0.4064)
			(stroke
				(width 0.1524)
				(type default)
			)
			(layer "B.SilkS")
		)
		(fp_line
			(start -0.7874 0.4064)
			(end 0.7874 0.4064)
			(stroke
				(width 0.1524)
				(type default)
			)
			(layer "B.SilkS")
		)
		(fp_line
			(start 0.7874 -0.4064)
			(end -0.7874 -0.4064)
			(stroke
				(width 0.1524)
				(type default)
			)
			(layer "B.SilkS")
		)
		(fp_line
			(start 0.7874 0.4064)
			(end 0.7874 -0.4064)
			(stroke
				(width 0.1524)
				(type default)
			)
			(layer "B.SilkS")
		)
		(fp_line
			(start -0.67945 -0.3048)
			(end -0.67945 0.3048)
			(stroke
				(width 0.1)
				(type default)
			)
			(layer "B.Fab")
		)
		(fp_line
			(start -0.67945 0.3048)
			(end -0.120396 0.3048)
			(stroke
				(width 0.1)
				(type default)
			)
			(layer "B.Fab")
		)
		(fp_line
			(start -0.12065 -0.3048)
			(end -0.67945 -0.3048)
			(stroke
				(width 0.1)
				(type default)
			)
			(layer "B.Fab")
		)
		(fp_line
			(start -0.12065 -0.2794)
			(end -0.12065 -0.3048)
			(stroke
				(width 0.1)
				(type default)
			)
			(layer "B.Fab")
		)
		(fp_line
			(start -0.120396 0.2794)
			(end 0.12065 0.2794)
			(stroke
				(width 0.1)
				(type default)
			)
			(layer "B.Fab")
		)
		(fp_line
			(start -0.120396 0.3048)
			(end -0.120396 0.2794)
			(stroke
				(width 0.1)
				(type default)
			)
			(layer "B.Fab")
		)
		(fp_line
			(start 0.12065 -0.305054)
			(end 0.12065 -0.2794)
			(stroke
				(width 0.1)
				(type default)
			)
			(layer "B.Fab")
		)
		(fp_line
			(start 0.12065 -0.2794)
			(end -0.12065 -0.2794)
			(stroke
				(width 0.1)
				(type default)
			)
			(layer "B.Fab")
		)
		(fp_line
			(start 0.12065 0.2794)
			(end 0.12065 0.3048)
			(stroke
				(width 0.1)
				(type default)
			)
			(layer "B.Fab")
		)
		(fp_line
			(start 0.12065 0.3048)
			(end 0.67945 0.3048)
			(stroke
				(width 0.1)
				(type default)
			)
			(layer "B.Fab")
		)
		(fp_line
			(start 0.67945 -0.305054)
			(end 0.12065 -0.305054)
			(stroke
				(width 0.1)
				(type default)
			)
			(layer "B.Fab")
		)
		(fp_line
			(start 0.67945 0.3048)
			(end 0.67945 -0.305054)
			(stroke
				(width 0.1)
				(type default)
			)
			(layer "B.Fab")
		)
		(pad "1" smd circle
			(at 0.40005 0 180)
			(size 0 0)
			(layers "B.Cu" "B.Mask" "B.Paste")
			(net "PVCCINFAON_CPU1_VOS2")
		)
		(pad "2" smd circle
			(at -0.40005 0 180)
			(size 0 0)
			(layers "B.Cu" "B.Mask" "B.Paste")
			(net "PVCCINFAON_CPU1")
		)
	)
)
